(kicad_pcb
	(version 20260206)
	(generator "pcbnew")
	(generator_version "10.0")
	(general
		(thickness 1.6)
		(legacy_teardrops no)
	)
	(paper "A4")
	(title_block
		(title "dpb — 14545-sa.0730WZS0815.brd")
		(comment 1 "Honey Badger (Wiwynn) / footprints 324-331 of 1066")
	)
	(layers
		(0 "F.Cu" signal "TOP")
		(4 "In1.Cu" signal "L2GND")
		(6 "In2.Cu" signal "L3")
		(8 "In3.Cu" signal "L4VCC")
		(10 "In4.Cu" signal "L5VCC")
		(12 "In5.Cu" signal "L6")
		(14 "In6.Cu" signal "L7GND")
		(2 "B.Cu" signal "BOTTOM")
		(9 "F.Adhes" user "F.Adhesive")
		(11 "B.Adhes" user "B.Adhesive")
		(13 "F.Paste" user "Package Geometry/Pastemask Top")
		(15 "B.Paste" user "Package Geometry/Pastemask Bottom")
		(5 "F.SilkS" user "Ref Des/Silkscreen Top")
		(7 "B.SilkS" user "Ref Des/Silkscreen Bottom")
		(1 "F.Mask" user "Board Geometry/Soldermask Top")
		(3 "B.Mask" user "Board Geometry/Soldermask Bottom")
		(17 "Dwgs.User" user "User.Drawings")
		(19 "Cmts.User" user "User.Comments")
		(21 "Eco1.User" user "User.Eco1")
		(23 "Eco2.User" user "User.Eco2")
		(25 "Edge.Cuts" user "Board Geometry/Outline")
		(27 "Margin" user)
		(31 "F.CrtYd" user "Package Geometry/Place Bound Top")
		(29 "B.CrtYd" user "Package Geometry/Place Bound Bottom")
		(35 "F.Fab" user "Ref Des/Assembly Top")
		(33 "B.Fab" user "Ref Des/Assembly Bottom")
	)
	(footprint ""
		(layer "F.Cu")
		(at 7.111746 -499.5037 180)
		(property "Reference" "PR46"
			(at 0 0 180)
			(layer "F.SilkS")
			(hide yes)
			(effects
				(font
					(size 1.27 1.27)
				)
			)
		)
		(property "Value" "115KR2F-GP"
			(at 0.064008 -3.993896 180)
			(unlocked yes)
			(layer "F.Fab")
			(hide yes)
			(effects
				(font
					(size 1.016 1.016)
					(thickness 0.1524)
				)
			)
		)
		(property "Device Type" "R402H16"
			(at 0.064008 -5.517896 180)
			(unlocked yes)
			(layer "F.Fab")
			(hide yes)
			(effects
				(font
					(size 1.016 1.016)
					(thickness 0.1524)
				)
			)
		)
		(duplicate_pad_numbers_are_jumpers no)
		(fp_line
			(start 0.508 -0.9398)
			(end -0.508 -0.9398)
			(stroke
				(width 0.1524)
				(type default)
			)
			(layer "F.SilkS")
		)
		(fp_line
			(start -0.508 -0.9398)
			(end -0.508 0.9398)
			(stroke
				(width 0.1524)
				(type default)
			)
			(layer "F.SilkS")
		)
		(fp_rect
			(start -0.508 0.9398)
			(end 0.508 -0.9398)
			(stroke
				(width 0)
				(type default)
			)
			(fill no)
			(layer "F.CrtYd")
		)
		(fp_rect
			(start -0.508 0.9398)
			(end 0.508 -0.9398)
			(stroke
				(width 0)
				(type default)
			)
			(fill no)
			(layer "F.Fab")
		)
		(pad "1" smd custom
			(at 0 -0.4445 180)
			(size 0.1397 0.1397)
			(layers "F.Cu" "F.Mask" "F.Paste")
			(net "P5VC_TRIP")
			(options
				(clearance outline)
				(anchor circle)
			)
			(primitives
				(gr_poly
					(pts
						(arc
							(start -0.1778 -0.2794)
							(mid -0.249642 -0.249642)
							(end -0.2794 -0.1778)
						)
						(arc
							(start -0.2794 0.1778)
							(mid -0.249642 0.249642)
							(end -0.1778 0.2794)
						)
						(arc
							(start 0.1778 0.2794)
							(mid 0.249642 0.249642)
							(end 0.2794 0.1778)
						)
						(arc
							(start 0.2794 -0.1778)
							(mid 0.249642 -0.249642)
							(end 0.1778 -0.2794)
						)
					)
					(width 0)
					(fill yes)
				)
			)
		)
		(pad "2" smd custom
			(at 0 0.4445 180)
			(size 0.1397 0.1397)
			(layers "F.Cu" "F.Mask" "F.Paste")
			(net "P5VC_AGND")
			(options
				(clearance outline)
				(anchor circle)
			)
			(primitives
				(gr_poly
					(pts
						(arc
							(start -0.1778 -0.2794)
							(mid -0.249642 -0.249642)
							(end -0.2794 -0.1778)
						)
						(arc
							(start -0.2794 0.1778)
							(mid -0.249642 0.249642)
							(end -0.1778 0.2794)
						)
						(arc
							(start 0.1778 0.2794)
							(mid 0.249642 0.249642)
							(end 0.2794 0.1778)
						)
						(arc
							(start 0.2794 -0.1778)
							(mid 0.249642 -0.249642)
							(end 0.1778 -0.2794)
						)
					)
					(width 0)
					(fill yes)
				)
			)
		)
	)
	(footprint ""
		(layer "F.Cu")
		(at 195.58 -495.554 180)
		(property "Reference" "R408"
			(at 0 0 180)
			(layer "F.SilkS")
			(hide yes)
			(effects
				(font
					(size 1.27 1.27)
				)
			)
		)
		(property "Value" "0R2J-2-GP"
			(at 0.064008 -3.993896 180)
			(unlocked yes)
			(layer "F.Fab")
			(hide yes)
			(effects
				(font
					(size 1.016 1.016)
					(thickness 0.1524)
				)
			)
		)
		(property "Device Type" "R402H16"
			(at 0.064008 -5.517896 180)
			(unlocked yes)
			(layer "F.Fab")
			(hide yes)
			(effects
				(font
					(size 1.016 1.016)
					(thickness 0.1524)
				)
			)
		)
		(duplicate_pad_numbers_are_jumpers no)
		(fp_line
			(start 0.508 -0.9398)
			(end -0.508 -0.9398)
			(stroke
				(width 0.1524)
				(type default)
			)
			(layer "F.SilkS")
		)
		(fp_line
			(start -0.508 -0.9398)
			(end -0.508 0.9398)
			(stroke
				(width 0.1524)
				(type default)
			)
			(layer "F.SilkS")
		)
		(fp_rect
			(start -0.508 0.9398)
			(end 0.508 -0.9398)
			(stroke
				(width 0)
				(type default)
			)
			(fill no)
			(layer "F.CrtYd")
		)
		(fp_rect
			(start -0.508 0.9398)
			(end 0.508 -0.9398)
			(stroke
				(width 0)
				(type default)
			)
			(fill no)
			(layer "F.Fab")
		)
		(pad "1" smd custom
			(at 0 -0.4445 180)
			(size 0.1397 0.1397)
			(layers "F.Cu" "F.Mask" "F.Paste")
			(net "SW_HDD0_G")
			(options
				(clearance outline)
				(anchor circle)
			)
			(primitives
				(gr_poly
					(pts
						(arc
							(start -0.1778 -0.2794)
							(mid -0.249642 -0.249642)
							(end -0.2794 -0.1778)
						)
						(arc
							(start -0.2794 0.1778)
							(mid -0.249642 0.249642)
							(end -0.1778 0.2794)
						)
						(arc
							(start 0.1778 0.2794)
							(mid 0.249642 0.249642)
							(end 0.2794 0.1778)
						)
						(arc
							(start 0.2794 -0.1778)
							(mid 0.249642 -0.249642)
							(end 0.1778 -0.2794)
						)
					)
					(width 0)
					(fill yes)
				)
			)
		)
		(pad "2" smd custom
			(at 0 0.4445 180)
			(size 0.1397 0.1397)
			(layers "F.Cu" "F.Mask" "F.Paste")
			(net "SW_HDD0_R")
			(options
				(clearance outline)
				(anchor circle)
			)
			(primitives
				(gr_poly
					(pts
						(arc
							(start -0.1778 -0.2794)
							(mid -0.249642 -0.249642)
							(end -0.2794 -0.1778)
						)
						(arc
							(start -0.2794 0.1778)
							(mid -0.249642 0.249642)
							(end -0.1778 0.2794)
						)
						(arc
							(start 0.1778 0.2794)
							(mid 0.249642 0.249642)
							(end 0.2794 0.1778)
						)
						(arc
							(start 0.2794 -0.1778)
							(mid 0.249642 -0.249642)
							(end 0.1778 -0.2794)
						)
					)
					(width 0)
					(fill yes)
				)
			)
		)
	)
	(footprint ""
		(layer "F.Cu")
		(at 6.730746 -491.6297 180)
		(property "Reference" "TP24"
			(at 0 0 180)
			(layer "F.SilkS")
			(hide yes)
			(effects
				(font
					(size 1.27 1.27)
				)
			)
		)
		(property "Value" "TPAD32-GP"
			(at 0 -3.166364 180)
			(unlocked yes)
			(layer "F.Fab")
			(hide yes)
			(effects
				(font
					(size 1.016 1.016)
					(thickness 0.1524)
				)
			)
		)
		(property "Device Type" "TPAD32"
			(at 0 -4.690618 180)
			(unlocked yes)
			(layer "F.Fab")
			(hide yes)
			(effects
				(font
					(size 1.016 1.016)
					(thickness 0.1524)
				)
			)
		)
		(duplicate_pad_numbers_are_jumpers no)
		(fp_poly
			(pts
				(arc
					(start -0.4064 0)
					(mid 0.4064 0)
					(end -0.4064 0)
				)
			)
			(stroke
				(width 0)
				(type default)
			)
			(fill no)
			(layer "F.CrtYd")
		)
		(fp_poly
			(pts
				(arc
					(start -0.7112 0)
					(mid 0.7112 0)
					(end -0.7112 0)
				)
			)
			(stroke
				(width 0)
				(type default)
			)
			(fill no)
			(layer "F.Fab")
		)
		(pad "1" smd circle
			(at 0 0 180)
			(size 0.8128 0.8128)
			(layers "F.Cu" "F.Mask" "F.Paste")
			(net "P5VC_PGD")
		)
	)
	(footprint ""
		(layer "F.Cu")
		(at 32.258 -288.29)
		(property "Reference" "R570"
			(at 0 0 0)
			(layer "F.SilkS")
			(hide yes)
			(effects
				(font
					(size 1.27 1.27)
				)
			)
		)
		(property "Value" "300KR2F-GP"
			(at 0.064008 -3.993896 0)
			(unlocked yes)
			(layer "F.Fab")
			(hide yes)
			(effects
				(font
					(size 1.016 1.016)
					(thickness 0.1524)
				)
			)
		)
		(property "Device Type" "R402H16"
			(at 0.064008 -5.517896 0)
			(unlocked yes)
			(layer "F.Fab")
			(hide yes)
			(effects
				(font
					(size 1.016 1.016)
					(thickness 0.1524)
				)
			)
		)
		(duplicate_pad_numbers_are_jumpers no)
		(fp_line
			(start -0.508 -0.9398)
			(end -0.508 0.9398)
			(stroke
				(width 0.1524)
				(type default)
			)
			(layer "F.SilkS")
		)
		(fp_line
			(start 0.508 -0.9398)
			(end -0.508 -0.9398)
			(stroke
				(width 0.1524)
				(type default)
			)
			(layer "F.SilkS")
		)
		(fp_rect
			(start -0.508 0.9398)
			(end 0.508 -0.9398)
			(stroke
				(width 0)
				(type default)
			)
			(fill no)
			(layer "F.CrtYd")
		)
		(fp_rect
			(start -0.508 0.9398)
			(end 0.508 -0.9398)
			(stroke
				(width 0)
				(type default)
			)
			(fill no)
			(layer "F.Fab")
		)
		(pad "1" smd custom
			(at 0 -0.4445)
			(size 0.1397 0.1397)
			(layers "F.Cu" "F.Mask" "F.Paste")
			(net "SW_HDD7_N")
			(options
				(clearance outline)
				(anchor circle)
			)
			(primitives
				(gr_poly
					(pts
						(arc
							(start -0.1778 -0.2794)
							(mid -0.249642 -0.249642)
							(end -0.2794 -0.1778)
						)
						(arc
							(start -0.2794 0.1778)
							(mid -0.249642 0.249642)
							(end -0.1778 0.2794)
						)
						(arc
							(start 0.1778 0.2794)
							(mid 0.249642 0.249642)
							(end 0.2794 0.1778)
						)
						(arc
							(start 0.2794 -0.1778)
							(mid 0.249642 -0.249642)
							(end 0.1778 -0.2794)
						)
					)
					(width 0)
					(fill yes)
				)
			)
		)
		(pad "2" smd custom
			(at 0 0.4445)
			(size 0.1397 0.1397)
			(layers "F.Cu" "F.Mask" "F.Paste")
			(net "P12V")
			(options
				(clearance outline)
				(anchor circle)
			)
			(primitives
				(gr_poly
					(pts
						(arc
							(start -0.1778 -0.2794)
							(mid -0.249642 -0.249642)
							(end -0.2794 -0.1778)
						)
						(arc
							(start -0.2794 0.1778)
							(mid -0.249642 0.249642)
							(end -0.1778 0.2794)
						)
						(arc
							(start 0.1778 0.2794)
							(mid 0.249642 0.249642)
							(end 0.2794 0.1778)
						)
						(arc
							(start 0.2794 -0.1778)
							(mid 0.249642 -0.249642)
							(end 0.1778 -0.2794)
						)
					)
					(width 0)
					(fill yes)
				)
			)
		)
	)
	(footprint ""
		(layer "F.Cu")
		(at 194.31 -89.916 180)
		(property "Reference" "R567"
			(at 0 0 180)
			(layer "F.SilkS")
			(hide yes)
			(effects
				(font
					(size 1.27 1.27)
				)
			)
		)
		(property "Value" "300KR2F-GP"
			(at 0.064008 -3.993896 180)
			(unlocked yes)
			(layer "F.Fab")
			(hide yes)
			(effects
				(font
					(size 1.016 1.016)
					(thickness 0.1524)
				)
			)
		)
		(property "Device Type" "R402H16"
			(at 0.064008 -5.517896 180)
			(unlocked yes)
			(layer "F.Fab")
			(hide yes)
			(effects
				(font
					(size 1.016 1.016)
					(thickness 0.1524)
				)
			)
		)
		(duplicate_pad_numbers_are_jumpers no)
		(fp_line
			(start 0.508 -0.9398)
			(end -0.508 -0.9398)
			(stroke
				(width 0.1524)
				(type default)
			)
			(layer "F.SilkS")
		)
		(fp_line
			(start -0.508 -0.9398)
			(end -0.508 0.9398)
			(stroke
				(width 0.1524)
				(type default)
			)
			(layer "F.SilkS")
		)
		(fp_rect
			(start -0.508 0.9398)
			(end 0.508 -0.9398)
			(stroke
				(width 0)
				(type default)
			)
			(fill no)
			(layer "F.CrtYd")
		)
		(fp_rect
			(start -0.508 0.9398)
			(end 0.508 -0.9398)
			(stroke
				(width 0)
				(type default)
			)
			(fill no)
			(layer "F.Fab")
		)
		(pad "1" smd custom
			(at 0 -0.4445 180)
			(size 0.1397 0.1397)
			(layers "F.Cu" "F.Mask" "F.Paste")
			(net "SW_HDD4_N")
			(options
				(clearance outline)
				(anchor circle)
			)
			(primitives
				(gr_poly
					(pts
						(arc
							(start -0.1778 -0.2794)
							(mid -0.249642 -0.249642)
							(end -0.2794 -0.1778)
						)
						(arc
							(start -0.2794 0.1778)
							(mid -0.249642 0.249642)
							(end -0.1778 0.2794)
						)
						(arc
							(start 0.1778 0.2794)
							(mid 0.249642 0.249642)
							(end 0.2794 0.1778)
						)
						(arc
							(start 0.2794 -0.1778)
							(mid 0.249642 -0.249642)
							(end 0.1778 -0.2794)
						)
					)
					(width 0)
					(fill yes)
				)
			)
		)
		(pad "2" smd custom
			(at 0 0.4445 180)
			(size 0.1397 0.1397)
			(layers "F.Cu" "F.Mask" "F.Paste")
			(net "P12V")
			(options
				(clearance outline)
				(anchor circle)
			)
			(primitives
				(gr_poly
					(pts
						(arc
							(start -0.1778 -0.2794)
							(mid -0.249642 -0.249642)
							(end -0.2794 -0.1778)
						)
						(arc
							(start -0.2794 0.1778)
							(mid -0.249642 0.249642)
							(end -0.1778 0.2794)
						)
						(arc
							(start 0.1778 0.2794)
							(mid 0.249642 0.249642)
							(end 0.2794 0.1778)
						)
						(arc
							(start 0.2794 -0.1778)
							(mid 0.249642 -0.249642)
							(end 0.1778 -0.2794)
						)
					)
					(width 0)
					(fill yes)
				)
			)
		)
	)
	(footprint ""
		(layer "F.Cu")
		(at 242.569746 -13.9827 90)
		(property "Reference" "PC1"
			(at 0 0 90)
			(layer "F.SilkS")
			(hide yes)
			(effects
				(font
					(size 1.27 1.27)
				)
			)
		)
		(property "Value" "SC22U25V5MX-GP"
			(at -0.0762 -6.1214 90)
			(unlocked yes)
			(layer "F.Fab")
			(hide yes)
			(effects
				(font
					(size 1.016 1.016)
					(thickness 0.1524)
				)
			)
		)
		(property "Device Type" "C805H58"
			(at -0.0762 -8.1534 90)
			(unlocked yes)
			(layer "F.Fab")
			(hide yes)
			(effects
				(font
					(size 1.016 1.016)
					(thickness 0.1524)
				)
			)
		)
		(duplicate_pad_numbers_are_jumpers no)
		(fp_line
			(start 0.635 0)
			(end -0.635 0)
			(stroke
				(width 0.508)
				(type default)
			)
			(layer "F.SilkS")
		)
		(fp_rect
			(start -0.9652 1.778)
			(end 0.9652 -1.778)
			(stroke
				(width 0)
				(type default)
			)
			(fill no)
			(layer "F.CrtYd")
		)
		(fp_poly
			(pts
				(xy -0.9652 -1.778) (xy 0.9652 -1.778) (xy 0.9652 1.778) (xy -0.9652 1.778)
			)
			(stroke
				(width 0)
				(type default)
			)
			(fill no)
			(layer "F.Fab")
		)
		(pad "1" smd rect
			(at 0 -0.9652 90)
			(size 1.397 1.143)
			(layers "F.Cu" "F.Mask" "F.Paste")
			(net "P5VA_12VIN")
		)
		(pad "2" smd rect
			(at 0 0.9652 90)
			(size 1.397 1.143)
			(layers "F.Cu" "F.Mask" "F.Paste")
			(net "GND")
		)
	)
	(footprint ""
		(layer "F.Cu")
		(at 33.043368 -475.171516 -90)
		(property "Reference" "C184"
			(at 0 0 270)
			(layer "F.SilkS")
			(hide yes)
			(effects
				(font
					(size 1.27 1.27)
				)
			)
		)
		(property "Value" "SCD01U50V2KX-1GP"
			(at 1.1811 -2.7051 270)
			(unlocked yes)
			(layer "F.Fab")
			(hide yes)
			(effects
				(font
					(size 1.016 1.016)
					(thickness 0.1524)
				)
			)
		)
		(property "Device Type" "C402H22"
			(at 1.1811 -4.2291 270)
			(unlocked yes)
			(layer "F.Fab")
			(hide yes)
			(effects
				(font
					(size 1.016 1.016)
					(thickness 0.1524)
				)
			)
		)
		(duplicate_pad_numbers_are_jumpers no)
		(fp_rect
			(start -0.4318 0.9525)
			(end 0.4318 -0.9525)
			(stroke
				(width 0)
				(type default)
			)
			(fill no)
			(layer "F.CrtYd")
		)
		(fp_rect
			(start -0.4318 0.9525)
			(end 0.4318 -0.9525)
			(stroke
				(width 0)
				(type default)
			)
			(fill no)
			(layer "F.Fab")
		)
		(pad "1" smd custom
			(at 0 -0.4445 270)
			(size 0.1524 0.1524)
			(layers "F.Cu" "F.Mask" "F.Paste")
			(net "SAS2X28_DRIVE_RX_N_B5")
			(options
				(clearance outline)
				(anchor circle)
			)
			(primitives
				(gr_poly
					(pts
						(arc
							(start 0.3048 -0.2032)
							(mid 0.275042 -0.275042)
							(end 0.2032 -0.3048)
						)
						(arc
							(start -0.2032 -0.3048)
							(mid -0.275042 -0.275042)
							(end -0.3048 -0.2032)
						)
						(arc
							(start -0.3048 0.2032)
							(mid -0.275042 0.275042)
							(end -0.2032 0.3048)
						)
						(arc
							(start 0.2032 0.3048)
							(mid 0.275042 0.275042)
							(end 0.3048 0.2032)
						)
					)
					(width 0)
					(fill yes)
				)
			)
		)
		(pad "2" smd custom
			(at 0 0.4445 270)
			(size 0.1524 0.1524)
			(layers "F.Cu" "F.Mask" "F.Paste")
			(net "SAS2X28_B_HDD5_RX_-")
			(options
				(clearance outline)
				(anchor circle)
			)
			(primitives
				(gr_poly
					(pts
						(arc
							(start 0.3048 -0.2032)
							(mid 0.275042 -0.275042)
							(end 0.2032 -0.3048)
						)
						(arc
							(start -0.2032 -0.3048)
							(mid -0.275042 -0.275042)
							(end -0.3048 -0.2032)
						)
						(arc
							(start -0.3048 0.2032)
							(mid -0.275042 0.275042)
							(end -0.2032 0.3048)
						)
						(arc
							(start 0.2032 0.3048)
							(mid 0.275042 0.275042)
							(end 0.3048 0.2032)
						)
					)
					(width 0)
					(fill yes)
				)
			)
		)
	)
	(footprint ""
		(layer "F.Cu")
		(at 72.681846 -492.6203)
		(property "Reference" "U16"
			(at 0 0 0)
			(layer "F.SilkS")
			(hide yes)
			(effects
				(font
					(size 1.27 1.27)
				)
			)
		)
		(property "Value" "74LVC1G08GW-1-GP"
			(at -2.3368 -8.6868 0)
			(unlocked yes)
			(layer "F.Fab")
			(hide yes)
			(effects
				(font
					(size 1.016 1.016)
					(thickness 0.1524)
				)
			)
		)
		(property "Device Type" "SC70-5H44"
			(at -2.3114 -10.414 0)
			(unlocked yes)
			(layer "F.Fab")
			(hide yes)
			(effects
				(font
					(size 1.016 1.016)
					(thickness 0.1524)
				)
			)
		)
		(duplicate_pad_numbers_are_jumpers no)
		(fp_line
			(start -1.27 -1.7018)
			(end 1.27 -1.7018)
			(stroke
				(width 0.1524)
				(type default)
			)
			(layer "F.SilkS")
		)
		(fp_line
			(start -1.27 1.7018)
			(end -1.27 -1.7018)
			(stroke
				(width 0.1524)
				(type default)
			)
			(layer "F.SilkS")
		)
		(fp_line
			(start 0.6604 -1.8034)
			(end 1.3843 -1.8034)
			(stroke
				(width 0.3302)
				(type default)
			)
			(layer "F.SilkS")
		)
		(fp_line
			(start 1.27 -1.7018)
			(end 1.27 1.7018)
			(stroke
				(width 0.1524)
				(type default)
			)
			(layer "F.SilkS")
		)
		(fp_line
			(start 1.27 1.7018)
			(end -1.27 1.7018)
			(stroke
				(width 0.1524)
				(type default)
			)
			(layer "F.SilkS")
		)
		(fp_line
			(start 1.3843 -1.8034)
			(end 1.3843 -1.1176)
			(stroke
				(width 0.3302)
				(type default)
			)
			(layer "F.SilkS")
		)
		(fp_rect
			(start -1.524 1.9558)
			(end 1.524 -1.9558)
			(stroke
				(width 0)
				(type default)
			)
			(fill no)
			(layer "F.CrtYd")
		)
		(fp_poly
			(pts
				(xy -1.524 -1.9558) (xy 1.524 -1.9558) (xy 1.524 1.9558) (xy -1.524 1.9558)
			)
			(stroke
				(width 0)
				(type default)
			)
			(fill no)
			(layer "F.Fab")
		)
		(pad "1" smd rect
			(at 0.65024 -0.8255)
			(size 0.4064 1.2192)
			(layers "F.Cu" "F.Mask" "F.Paste")
			(net "SAS2X28_B_HDD5_FLT")
		)
		(pad "2" smd rect
			(at 0 -0.8255)
			(size 0.4064 1.2192)
			(layers "F.Cu" "F.Mask" "F.Paste")
			(net "SAS2X28_A_HDD5_FLT")
		)
		(pad "3" smd rect
			(at -0.65024 -0.8255)
			(size 0.4064 1.2192)
			(layers "F.Cu" "F.Mask" "F.Paste")
			(net "GND")
		)
		(pad "4" smd rect
			(at -0.65024 0.8255)
			(size 0.4064 1.2192)
			(layers "F.Cu" "F.Mask" "F.Paste")
			(net "FLT_HDD5_DRIVE")
		)
		(pad "5" smd rect
			(at 0.65024 0.8255)
			(size 0.4064 1.2192)
			(layers "F.Cu" "F.Mask" "F.Paste")
			(net "P3V3")
		)
	)
)
